FILE_TYPE = MACRO_DRAWING;
SET COLOR_WIRE YELLOW;
SET COLOR_PROP ORANGE;
SET COLOR_DOT WHITE;
SET COLOR_ARC YELLOW;
SET COLOR_BODY GREEN;
SET COLOR_NOTE PURPLE;
SET PROP_DISPLAY VALUE;
SET PAGE_NUMBER P5;
FORCEADD QUANTA_TITLE_BLOCK_C..1
(-100 100);
FORCEPROP 1 LAST CUSTOM_TXT_CDS <NAME_2>
J 0
(-3275 150);
FORCEPROP 1 LAST CUSTOM_TXT_CDS <NAME_1>
J 0
(-3275 275);
FORCEPROP 1 LAST CUSTOM_TXT_CDS <Q_NUMBER>
J 0
(-1503 203);
DISPLAY 1.212766 (-1503 203);
FORCEPROP 1 LAST CUSTOM_TXT_CDS <Q_PROJ>
J 0
(-2482 202);
DISPLAY 1.212766 (-2482 202);
FORCEPROP 1 LAST CUSTOM_TXT_CDS <Q_REV>
J 0
(-284 203);
DISPLAY 1.212766 (-284 203);
FORCEPROP 1 LAST CUSTOM_TXT_CDS <CON_LAST_MODIFIED>
J 0
(-1985 115);
DISPLAY 0.978723 (-1985 115);
FORCEPROP 1 LAST CUSTOM_TXT_CDS <CON_PAGE_NUM> OF <CON_TOTAL_PAGES>
J 0
(-546 118);
DISPLAY 0.978723 (-546 118);
FORCEPROP 1 LAST Q_TITLE BLOCK DIAGRAM - SYSTEM
J 0
(-9350 175);
DISPLAY 2.446809 (-9350 175);
PAINT GREEN (-9350 175);
FORCEPROP 1 LAST Q_DEPT BU9
J 1
(-3863 149);
DISPLAY 1.957447 (-3863 149);
PAINT GREEN (-3863 149);
FORCEPROP 2 LAST CDS_LIB pure_quanta
J 0
(-100 100);
DISPLAY INVISIBLE (-100 100);
FORCEPROP 1 LAST CDS_LMAN_SYM_OUTLINE -9475,6775,100,-125
J 0
(-100 100);
DISPLAY 0.468085 (-100 100);
PAINT GREEN (-100 100);
DISPLAY INVISIBLE (-100 100);
FORCEPROP 2 LAST PAGE_BORDER TRUE
J 0
(-7990 5350);
DISPLAY 0.638298 (-7990 5350);
PAINT PINK (-7990 5350);
DISPLAY INVISIBLE (-7990 5350);
FORCEPROP 1 LAST COMMENT_BODY TRUE
J 0
(-88 87);
DISPLAY 0.978723 (-88 87);
PAINT GREEN (-88 87);
DISPLAY INVISIBLE (-88 87);
FORCEPROP 2 LAST CDS_XR_PAGE_TITLE CR-5 : @T6G_MB_LIB.T6G(SCH_1):PAGE5
J 0
(-7990 5350);
DISPLAY 0.638298 (-7990 5350);
PAINT PINK (-7990 5350);
DISPLAY INVISIBLE (-7990 5350);
FORCEPROP 2 LAST CUSTOM_TXT_CDS <XR_PAGE_TITLE>
J 0
(-7990 5350);
DISPLAY 0.638298 (-7990 5350);
PAINT PINK (-7990 5350);
DISPLAY INVISIBLE (-7990 5350);
FORCEPROP 0 LAST CDS_CON_LAST_MODIFIED Tue Mar 08 15:46:34 2022
J 0
(-1985 115);
DISPLAY INVISIBLE (-1985 115);
QUIT
